# BASEBOARD_FAB2 (Tioga Pass) — schematic netlist excerpt (pin names and nets, part order shuffled) for the footprints in the layout excerpt that follows; sources: Cadence DE-HDL packaged netlist, KiCad conversion of Wiwynn_Tioga_Pass_MB.brd

C2L4  CAP_A  0.01UF 25V 10% X7R  pkg 0402V  page 173 : A = SATA6G_PCH_PCIE_UP_SATA_RXP<3> ; B = SATA6G_P3_RX_C_DP
C2N5  CAP_A  1.0UF 6.3V 10% X6S  pkg 0402V  page 127 : A = P1V05_PCH_STBY_KR_PLL ; B = GND
C6P22  CAP  10UF 16V 10% X6S  pkg 0805  page 202 : A = VR_FET_SW_P12V_STBY_PVCCIN_CPU0 ; B = GND

(kicad_pcb
	(version 20260206)
	(generator "pcbnew")
	(generator_version "10.0")
	(general
		(thickness 1.6)
		(legacy_teardrops no)
	)
	(paper "A4")
	(title_block
		(title "Wiwynn_Tioga_Pass_MB.brd")
		(comment 1 "Tioga Pass / footprints 4680-4682 of 4770")
	)
	(layers
		(0 "F.Cu" signal "TOP")
		(4 "In1.Cu" signal "L2GND")
		(6 "In2.Cu" signal "L3")
		(8 "In3.Cu" signal "L4GND")
		(10 "In4.Cu" signal "L5")
		(12 "In5.Cu" signal "L6GND")
		(14 "In6.Cu" signal "L7VCC")
		(16 "In7.Cu" signal "L8VCC")
		(18 "In8.Cu" signal "L9GND")
		(20 "In9.Cu" signal "L10")
		(22 "In10.Cu" signal "L11GND")
		(24 "In11.Cu" signal "L12")
		(26 "In12.Cu" signal "L13GND")
		(2 "B.Cu" signal "BOTTOM")
		(9 "F.Adhes" user "F.Adhesive")
		(11 "B.Adhes" user "B.Adhesive")
		(13 "F.Paste" user "Package Geometry/Pastemask Top")
		(15 "B.Paste" user "Package Geometry/Pastemask Bottom")
		(5 "F.SilkS" user "Ref Des/Silkscreen Top")
		(7 "B.SilkS" user "Ref Des/Silkscreen Bottom")
		(1 "F.Mask" user "Board Geometry/Soldermask Top")
		(3 "B.Mask" user "Board Geometry/Soldermask Bottom")
		(17 "Dwgs.User" user "User.Drawings")
		(19 "Cmts.User" user "User.Comments")
		(21 "Eco1.User" user "User.Eco1")
		(23 "Eco2.User" user "User.Eco2")
		(25 "Edge.Cuts" user "Board Geometry/Outline")
		(27 "Margin" user)
		(31 "F.CrtYd" user "Package Geometry/Place Bound Top")
		(29 "B.CrtYd" user "Package Geometry/Place Bound Bottom")
		(35 "F.Fab" user "Ref Des/Assembly Top")
		(33 "B.Fab" user "Ref Des/Assembly Bottom")
	)
	(footprint ""
		(layer "B.Cu")
		(at 400.177 -111.379)
		(property "Reference" "C2N5"
			(at 0 0 0)
			(layer "B.SilkS")
			(hide yes)
			(effects
				(font
					(size 1.27 1.27)
				)
				(justify mirror)
			)
		)
		(property "Value" ""
			(at 0 0 0)
			(layer "B.Fab")
			(effects
				(font
					(size 1.27 1.27)
				)
				(justify mirror)
			)
		)
		(duplicate_pad_numbers_are_jumpers no)
		(fp_poly
			(pts
				(xy -0.3048 -0.1016) (xy -0.3048 0.9906) (xy 0.3048 0.9906) (xy 0.3048 -0.1016)
			)
			(stroke
				(width 0)
				(type default)
			)
			(fill no)
			(layer "B.CrtYd")
		)
		(fp_line
			(start -0.3048 -0.1016)
			(end 0.3048 -0.1016)
			(stroke
				(width 0.1)
				(type default)
			)
			(layer "B.Fab")
		)
		(fp_line
			(start -0.3048 0.9906)
			(end -0.3048 -0.1016)
			(stroke
				(width 0.1)
				(type default)
			)
			(layer "B.Fab")
		)
		(fp_line
			(start 0.3048 -0.1016)
			(end 0.3048 0.9906)
			(stroke
				(width 0.1)
				(type default)
			)
			(layer "B.Fab")
		)
		(fp_line
			(start 0.3048 0.9906)
			(end -0.3048 0.9906)
			(stroke
				(width 0.1)
				(type default)
			)
			(layer "B.Fab")
		)
		(pad "1" smd rect
			(at 0 0 180)
			(size 0.508 0.508)
			(layers "B.Cu" "B.Mask" "B.Paste")
			(net "P1V05_PCH_STBY_KR_PLL")
		)
		(pad "2" smd rect
			(at 0 0.889 180)
			(size 0.508 0.508)
			(layers "B.Cu" "B.Mask" "B.Paste")
			(net "GND")
		)
		(zone
			(layer "B.Cu")
			(hatch none 0.5)
			(connect_pads
				(clearance 0)
			)
			(min_thickness 0.25)
			(keepout
				(tracks allowed)
				(vias not_allowed)
				(pads allowed)
				(copperpour not_allowed)
				(footprints allowed)
			)
			(placement
				(enabled no)
				(sheetname "")
			)
			(fill
				(thermal_gap 0.5)
				(thermal_bridge_width 0.5)
				(island_removal_mode 0)
			)
			(polygon
				(pts
					(xy 400.431 -111.125) (xy 399.923 -111.125) (xy 399.923 -110.744) (xy 400.431 -110.744)
				)
			)
		)
		(zone
			(layer "B.Cu")
			(hatch none 0.5)
			(connect_pads
				(clearance 0)
			)
			(min_thickness 0.25)
			(keepout
				(tracks not_allowed)
				(vias allowed)
				(pads allowed)
				(copperpour not_allowed)
				(footprints allowed)
			)
			(placement
				(enabled no)
				(sheetname "")
			)
			(fill
				(thermal_gap 0.5)
				(thermal_bridge_width 0.5)
				(island_removal_mode 0)
			)
			(polygon
				(pts
					(xy 400.431 -110.744) (xy 399.923 -110.744) (xy 399.923 -111.125) (xy 400.431 -111.125)
				)
			)
		)
	)
	(footprint ""
		(layer "B.Cu")
		(at 197.848728 -67.978782 90)
		(property "Reference" "C6P22"
			(at 0 0 90)
			(layer "B.SilkS")
			(hide yes)
			(effects
				(font
					(size 1.27 1.27)
				)
				(justify mirror)
			)
		)
		(property "Value" ""
			(at 0 0 90)
			(layer "B.Fab")
			(effects
				(font
					(size 1.27 1.27)
				)
				(justify mirror)
			)
		)
		(duplicate_pad_numbers_are_jumpers no)
		(fp_rect
			(start -0.7239 -0.2159)
			(end 0.7239 1.9939)
			(stroke
				(width 0)
				(type default)
			)
			(fill no)
			(layer "B.CrtYd")
		)
		(fp_line
			(start 0.7239 -0.2159)
			(end 0.7239 1.9939)
			(stroke
				(width 0.1)
				(type default)
			)
			(layer "B.Fab")
		)
		(fp_line
			(start -0.7239 -0.2159)
			(end 0.7239 -0.2159)
			(stroke
				(width 0.1)
				(type default)
			)
			(layer "B.Fab")
		)
		(fp_line
			(start 0.7239 1.9939)
			(end -0.7239 1.9939)
			(stroke
				(width 0.1)
				(type default)
			)
			(layer "B.Fab")
		)
		(fp_line
			(start -0.7239 1.9939)
			(end -0.7239 -0.2159)
			(stroke
				(width 0.1)
				(type default)
			)
			(layer "B.Fab")
		)
		(pad "1" smd rect
			(at 0 0 270)
			(size 1.27 1.016)
			(layers "B.Cu" "B.Mask" "B.Paste")
			(net "VR_FET_SW_P12V_STBY_PVCCIN_CPU0")
		)
		(pad "2" smd rect
			(at 0 1.778 270)
			(size 1.27 1.016)
			(layers "B.Cu" "B.Mask" "B.Paste")
			(net "GND")
		)
		(zone
			(layer "B.Cu")
			(hatch none 0.5)
			(connect_pads
				(clearance 0)
			)
			(min_thickness 0.25)
			(keepout
				(tracks not_allowed)
				(vias allowed)
				(pads allowed)
				(copperpour not_allowed)
				(footprints allowed)
			)
			(placement
				(enabled no)
				(sheetname "")
			)
			(fill
				(thermal_gap 0.5)
				(thermal_bridge_width 0.5)
				(island_removal_mode 0)
			)
			(polygon
				(pts
					(xy 198.356728 -67.343782) (xy 199.118728 -67.343782) (xy 199.118728 -68.613782) (xy 198.356728 -68.613782)
				)
			)
		)
	)
	(footprint ""
		(layer "B.Cu")
		(at 420.624 -154.94 90)
		(property "Reference" "C2L4"
			(at 0 0 90)
			(layer "B.SilkS")
			(hide yes)
			(effects
				(font
					(size 1.27 1.27)
				)
				(justify mirror)
			)
		)
		(property "Value" ""
			(at 0 0 90)
			(layer "B.Fab")
			(effects
				(font
					(size 1.27 1.27)
				)
				(justify mirror)
			)
		)
		(duplicate_pad_numbers_are_jumpers no)
		(fp_poly
			(pts
				(xy -0.3048 -0.1016) (xy -0.3048 0.9906) (xy 0.3048 0.9906) (xy 0.3048 -0.1016)
			)
			(stroke
				(width 0)
				(type default)
			)
			(fill no)
			(layer "B.CrtYd")
		)
		(fp_line
			(start 0.3048 -0.1016)
			(end 0.3048 0.9906)
			(stroke
				(width 0.1)
				(type default)
			)
			(layer "B.Fab")
		)
		(fp_line
			(start -0.3048 -0.1016)
			(end 0.3048 -0.1016)
			(stroke
				(width 0.1)
				(type default)
			)
			(layer "B.Fab")
		)
		(fp_line
			(start 0.3048 0.9906)
			(end -0.3048 0.9906)
			(stroke
				(width 0.1)
				(type default)
			)
			(layer "B.Fab")
		)
		(fp_line
			(start -0.3048 0.9906)
			(end -0.3048 -0.1016)
			(stroke
				(width 0.1)
				(type default)
			)
			(layer "B.Fab")
		)
		(pad "1" smd rect
			(at 0 0 270)
			(size 0.508 0.508)
			(layers "B.Cu" "B.Mask" "B.Paste")
			(net "SATA6G_PCH_PCIE_UP_SATA_RXP<3>")
		)
		(pad "2" smd rect
			(at 0 0.889 270)
			(size 0.508 0.508)
			(layers "B.Cu" "B.Mask" "B.Paste")
			(net "SATA6G_P3_RX_C_DP")
		)
		(zone
			(layer "B.Cu")
			(hatch none 0.5)
			(connect_pads
				(clearance 0)
			)
			(min_thickness 0.25)
			(keepout
				(tracks allowed)
				(vias not_allowed)
				(pads allowed)
				(copperpour not_allowed)
				(footprints allowed)
			)
			(placement
				(enabled no)
				(sheetname "")
			)
			(fill
				(thermal_gap 0.5)
				(thermal_bridge_width 0.5)
				(island_removal_mode 0)
			)
			(polygon
				(pts
					(xy 420.878 -155.194) (xy 420.878 -154.686) (xy 421.259 -154.686) (xy 421.259 -155.194)
				)
			)
		)
		(zone
			(layer "B.Cu")
			(hatch none 0.5)
			(connect_pads
				(clearance 0)
			)
			(min_thickness 0.25)
			(keepout
				(tracks not_allowed)
				(vias allowed)
				(pads allowed)
				(copperpour not_allowed)
				(footprints allowed)
			)
			(placement
				(enabled no)
				(sheetname "")
			)
			(fill
				(thermal_gap 0.5)
				(thermal_bridge_width 0.5)
				(island_removal_mode 0)
			)
			(polygon
				(pts
					(xy 421.259 -155.194) (xy 421.259 -154.686) (xy 420.878 -154.686) (xy 420.878 -155.194)
				)
			)
		)
	)
)
